# T6G (Grand Teton) — schematic netlist excerpt (pin names and nets, part order shuffled) for the footprints in the layout excerpt that follows; sources: Cadence DE-HDL packaged netlist, KiCad conversion of 04192023_DAF0TMB3IC0_F0TG_MB_C_brd_V02_OCP.brd

R4189  Q_RES  1K 1% CHIP  pkg 0402LF  page 235 : A = U271_1_ADD2 ; B = GND
R3827  Q_RES  0 5% CHIP  pkg 0402LF  page 140 : A = P12V_OCP_UV_2_R ; B = P12V_OCP_UV_2

(kicad_pcb
	(version 20260206)
	(generator "pcbnew")
	(generator_version "10.0")
	(general
		(thickness 1.6)
		(legacy_teardrops no)
	)
	(paper "A4")
	(title_block
		(title "04192023_DAF0TMB3IC0_F0TG_MB_C_brd_V02_OCP.brd")
		(comment 1 "Grand Teton / footprints 1986-1987 of 8354")
	)
	(layers
		(0 "F.Cu" signal "TOP")
		(4 "In1.Cu" signal "GND")
		(6 "In2.Cu" signal "IN1")
		(8 "In3.Cu" signal "GND1")
		(10 "In4.Cu" signal "IN2")
		(12 "In5.Cu" signal "GND2")
		(14 "In6.Cu" signal "IN3")
		(16 "In7.Cu" signal "GND3")
		(18 "In8.Cu" signal "VCC")
		(20 "In9.Cu" signal "VCC1")
		(22 "In10.Cu" signal "GND4")
		(24 "In11.Cu" signal "IN4")
		(26 "In12.Cu" signal "GND5")
		(28 "In13.Cu" signal "IN5")
		(30 "In14.Cu" signal "GND6")
		(32 "In15.Cu" signal "IN6")
		(34 "In16.Cu" signal "GND7")
		(2 "B.Cu" signal "BOTTOM")
		(9 "F.Adhes" user "F.Adhesive")
		(11 "B.Adhes" user "B.Adhesive")
		(13 "F.Paste" user "Package Geometry/Pastemask Top")
		(15 "B.Paste" user "Package Geometry/Pastemask Bottom")
		(5 "F.SilkS" user "Ref Des/Silkscreen Top")
		(7 "B.SilkS" user "Ref Des/Silkscreen Bottom")
		(1 "F.Mask" user "Board Geometry/Soldermask Top")
		(3 "B.Mask" user "Board Geometry/Soldermask Bottom")
		(17 "Dwgs.User" user "User.Drawings")
		(19 "Cmts.User" user "User.Comments")
		(21 "Eco1.User" user "User.Eco1")
		(23 "Eco2.User" user "User.Eco2")
		(25 "Edge.Cuts" user "Board Geometry/Outline")
		(27 "Margin" user)
		(31 "F.CrtYd" user "Package Geometry/Place Bound Top")
		(29 "B.CrtYd" user "Package Geometry/Place Bound Bottom")
		(35 "F.Fab" user "Ref Des/Assembly Top")
		(33 "B.Fab" user "Ref Des/Assembly Bottom")
	)
	(footprint ""
		(layer "F.Cu")
		(at 303.353978 -13.41501)
		(property "Reference" "R4189"
			(at 0 0 0)
			(layer "F.SilkS")
			(hide yes)
			(effects
				(font
					(size 1.27 1.27)
				)
			)
		)
		(property "Value" ""
			(at 0 0 0)
			(layer "F.Fab")
			(effects
				(font
					(size 1.27 1.27)
				)
			)
		)
		(duplicate_pad_numbers_are_jumpers no)
		(fp_line
			(start -0.7874 -0.4064)
			(end 0.7874 -0.4064)
			(stroke
				(width 0.1524)
				(type default)
			)
			(layer "F.SilkS")
		)
		(fp_line
			(start -0.7874 0.4064)
			(end -0.7874 -0.4064)
			(stroke
				(width 0.1524)
				(type default)
			)
			(layer "F.SilkS")
		)
		(fp_line
			(start 0.7874 -0.4064)
			(end 0.7874 0.4064)
			(stroke
				(width 0.1524)
				(type default)
			)
			(layer "F.SilkS")
		)
		(fp_line
			(start 0.7874 0.4064)
			(end -0.7874 0.4064)
			(stroke
				(width 0.1524)
				(type default)
			)
			(layer "F.SilkS")
		)
		(fp_line
			(start -0.67945 -0.305054)
			(end -0.12065 -0.305054)
			(stroke
				(width 0.1)
				(type default)
			)
			(layer "F.Fab")
		)
		(fp_line
			(start -0.67945 0.3048)
			(end -0.67945 -0.305054)
			(stroke
				(width 0.1)
				(type default)
			)
			(layer "F.Fab")
		)
		(fp_line
			(start -0.12065 -0.305054)
			(end -0.12065 -0.2794)
			(stroke
				(width 0.1)
				(type default)
			)
			(layer "F.Fab")
		)
		(fp_line
			(start -0.12065 -0.2794)
			(end 0.12065 -0.2794)
			(stroke
				(width 0.1)
				(type default)
			)
			(layer "F.Fab")
		)
		(fp_line
			(start -0.12065 0.2794)
			(end -0.12065 0.3048)
			(stroke
				(width 0.1)
				(type default)
			)
			(layer "F.Fab")
		)
		(fp_line
			(start -0.12065 0.3048)
			(end -0.67945 0.3048)
			(stroke
				(width 0.1)
				(type default)
			)
			(layer "F.Fab")
		)
		(fp_line
			(start 0.120396 0.2794)
			(end -0.12065 0.2794)
			(stroke
				(width 0.1)
				(type default)
			)
			(layer "F.Fab")
		)
		(fp_line
			(start 0.120396 0.3048)
			(end 0.120396 0.2794)
			(stroke
				(width 0.1)
				(type default)
			)
			(layer "F.Fab")
		)
		(fp_line
			(start 0.12065 -0.3048)
			(end 0.67945 -0.3048)
			(stroke
				(width 0.1)
				(type default)
			)
			(layer "F.Fab")
		)
		(fp_line
			(start 0.12065 -0.2794)
			(end 0.12065 -0.3048)
			(stroke
				(width 0.1)
				(type default)
			)
			(layer "F.Fab")
		)
		(fp_line
			(start 0.67945 -0.3048)
			(end 0.67945 0.3048)
			(stroke
				(width 0.1)
				(type default)
			)
			(layer "F.Fab")
		)
		(fp_line
			(start 0.67945 0.3048)
			(end 0.120396 0.3048)
			(stroke
				(width 0.1)
				(type default)
			)
			(layer "F.Fab")
		)
		(pad "1" smd circle
			(at -0.40005 0)
			(size 0 0)
			(layers "F.Cu" "F.Mask" "F.Paste")
			(net "U271_1_ADD2")
		)
		(pad "2" smd circle
			(at 0.40005 0)
			(size 0 0)
			(layers "F.Cu" "F.Mask" "F.Paste")
			(net "GND")
		)
	)
	(footprint ""
		(layer "F.Cu")
		(at 66.0654 -39.487348 90)
		(property "Reference" "R3827"
			(at 0 0 90)
			(layer "F.SilkS")
			(hide yes)
			(effects
				(font
					(size 1.27 1.27)
				)
			)
		)
		(property "Value" ""
			(at 0 0 90)
			(layer "F.Fab")
			(effects
				(font
					(size 1.27 1.27)
				)
			)
		)
		(duplicate_pad_numbers_are_jumpers no)
		(fp_line
			(start 0.7874 -0.4064)
			(end 0.7874 0.4064)
			(stroke
				(width 0.1524)
				(type default)
			)
			(layer "F.SilkS")
		)
		(fp_line
			(start -0.7874 -0.4064)
			(end 0.7874 -0.4064)
			(stroke
				(width 0.1524)
				(type default)
			)
			(layer "F.SilkS")
		)
		(fp_line
			(start 0.7874 0.4064)
			(end -0.7874 0.4064)
			(stroke
				(width 0.1524)
				(type default)
			)
			(layer "F.SilkS")
		)
		(fp_line
			(start -0.7874 0.4064)
			(end -0.7874 -0.4064)
			(stroke
				(width 0.1524)
				(type default)
			)
			(layer "F.SilkS")
		)
		(fp_line
			(start -0.12065 -0.305054)
			(end -0.12065 -0.2794)
			(stroke
				(width 0.1)
				(type default)
			)
			(layer "F.Fab")
		)
		(fp_line
			(start -0.67945 -0.305054)
			(end -0.12065 -0.305054)
			(stroke
				(width 0.1)
				(type default)
			)
			(layer "F.Fab")
		)
		(fp_line
			(start 0.67945 -0.3048)
			(end 0.67945 0.3048)
			(stroke
				(width 0.1)
				(type default)
			)
			(layer "F.Fab")
		)
		(fp_line
			(start 0.12065 -0.3048)
			(end 0.67945 -0.3048)
			(stroke
				(width 0.1)
				(type default)
			)
			(layer "F.Fab")
		)
		(fp_line
			(start 0.12065 -0.2794)
			(end 0.12065 -0.3048)
			(stroke
				(width 0.1)
				(type default)
			)
			(layer "F.Fab")
		)
		(fp_line
			(start -0.12065 -0.2794)
			(end 0.12065 -0.2794)
			(stroke
				(width 0.1)
				(type default)
			)
			(layer "F.Fab")
		)
		(fp_line
			(start 0.120396 0.2794)
			(end -0.12065 0.2794)
			(stroke
				(width 0.1)
				(type default)
			)
			(layer "F.Fab")
		)
		(fp_line
			(start -0.12065 0.2794)
			(end -0.12065 0.3048)
			(stroke
				(width 0.1)
				(type default)
			)
			(layer "F.Fab")
		)
		(fp_line
			(start 0.67945 0.3048)
			(end 0.120396 0.3048)
			(stroke
				(width 0.1)
				(type default)
			)
			(layer "F.Fab")
		)
		(fp_line
			(start 0.120396 0.3048)
			(end 0.120396 0.2794)
			(stroke
				(width 0.1)
				(type default)
			)
			(layer "F.Fab")
		)
		(fp_line
			(start -0.12065 0.3048)
			(end -0.67945 0.3048)
			(stroke
				(width 0.1)
				(type default)
			)
			(layer "F.Fab")
		)
		(fp_line
			(start -0.67945 0.3048)
			(end -0.67945 -0.305054)
			(stroke
				(width 0.1)
				(type default)
			)
			(layer "F.Fab")
		)
		(pad "1" smd circle
			(at -0.40005 0 90)
			(size 0 0)
			(layers "F.Cu" "F.Mask" "F.Paste")
			(net "P12V_OCP_UV_2_R")
		)
		(pad "2" smd circle
			(at 0.40005 0 90)
			(size 0 0)
			(layers "F.Cu" "F.Mask" "F.Paste")
			(net "P12V_OCP_UV_2")
		)
	)
)
